(kicad_pcb
	(version 20260206)
	(generator "pcbnew")
	(generator_version "10.0")
	(general
		(thickness 1.6)
		(legacy_teardrops no)
	)
	(paper "A4")
	(title_block
		(title "03242023_DA0F0TMBIJ0_F0T_Motherboard_J_brd_V01_OCP.brd")
		(comment 1 "Grand Teton / footprint 3039 of 6105 (U2), pads 2255-2362 of 4677")
	)
	(layers
		(0 "F.Cu" signal "TOP")
		(4 "In1.Cu" signal "GND")
		(6 "In2.Cu" signal "IN1")
		(8 "In3.Cu" signal "GND1")
		(10 "In4.Cu" signal "IN2")
		(12 "In5.Cu" signal "GND2")
		(14 "In6.Cu" signal "IN3")
		(16 "In7.Cu" signal "GND3")
		(18 "In8.Cu" signal "VCC")
		(20 "In9.Cu" signal "VCC1")
		(22 "In10.Cu" signal "GND4")
		(24 "In11.Cu" signal "IN4")
		(26 "In12.Cu" signal "GND5")
		(28 "In13.Cu" signal "IN5")
		(30 "In14.Cu" signal "GND6")
		(32 "In15.Cu" signal "IN6")
		(34 "In16.Cu" signal "GND7")
		(2 "B.Cu" signal "BOTTOM")
		(9 "F.Adhes" user "F.Adhesive")
		(11 "B.Adhes" user "B.Adhesive")
		(13 "F.Paste" user "Package Geometry/Pastemask Top")
		(15 "B.Paste" user "Package Geometry/Pastemask Bottom")
		(5 "F.SilkS" user "Ref Des/Silkscreen Top")
		(7 "B.SilkS" user "Ref Des/Silkscreen Bottom")
		(1 "F.Mask" user "Board Geometry/Soldermask Top")
		(3 "B.Mask" user "Board Geometry/Soldermask Bottom")
		(17 "Dwgs.User" user "User.Drawings")
		(19 "Cmts.User" user "User.Comments")
		(21 "Eco1.User" user "User.Eco1")
		(23 "Eco2.User" user "User.Eco2")
		(25 "Edge.Cuts" user "Board Geometry/Outline")
		(27 "Margin" user)
		(31 "F.CrtYd" user "Package Geometry/Place Bound Top")
		(29 "B.CrtYd" user "Package Geometry/Place Bound Bottom")
		(35 "F.Fab" user "Ref Des/Assembly Top")
		(33 "B.Fab" user "Ref Des/Assembly Bottom")
	)
	(footprint ""
		(layer "F.Cu")
		(at 359.870248 -251.76988 90)
		(property "Reference" "U2"
			(at -74.416158 -44.488608 0)
			(unlocked yes)
			(layer "F.SilkS")
			(effects
				(font
					(size 1.6002 1.1938)
					(thickness 0.1524)
				)
				(justify left)
			)
		)
		(property "Value" ""
			(at 0 0 90)
			(layer "F.Fab")
			(effects
				(font
					(size 1.27 1.27)
				)
			)
		)
		(duplicate_pad_numbers_are_jumpers no)
		(pad "CV85" smd circle
			(at 32.541718 9.217914 270)
			(size 0.4318 0.4318)
			(layers "F.Cu" "F.Mask" "F.Paste")
			(net "P5E_CPU0_PE3_TX_DN<13>")
		)
		(pad "CV87" smd circle
			(at 34.169604 9.217914 270)
			(size 0.4318 0.4318)
			(layers "F.Cu" "F.Mask" "F.Paste")
			(net "GND")
		)
		(pad "CV89" smd circle
			(at 35.797236 9.217914 270)
			(size 0.4318 0.4318)
			(layers "F.Cu" "F.Mask" "F.Paste")
			(net "P5E_CPU0_PE3_RX_DN<14>")
		)
		(pad "CV91" smd oval
			(at 37.425122 9.217914)
			(size 0.381 0.4826)
			(drill
				(offset 0 -0.0508)
			)
			(layers "F.Cu" "F.Mask" "F.Paste")
			(net "GND")
		)
		(pad "CW1" smd oval
			(at -37.425122 9.578086 180)
			(size 0.381 0.4826)
			(drill
				(offset 0 -0.0508)
			)
			(layers "F.Cu" "F.Mask" "F.Paste")
			(net "GND")
		)
		(pad "CW3" smd circle
			(at -35.797236 9.578086 270)
			(size 0.4318 0.4318)
			(layers "F.Cu" "F.Mask" "F.Paste")
			(net "UPI_CPU1_CPU0_P0P1_DP<14>")
		)
		(pad "CW5" smd circle
			(at -34.169604 9.578086 270)
			(size 0.4318 0.4318)
			(layers "F.Cu" "F.Mask" "F.Paste")
			(net "GND")
		)
		(pad "CW7" smd circle
			(at -32.541718 9.578086 270)
			(size 0.4318 0.4318)
			(layers "F.Cu" "F.Mask" "F.Paste")
			(net "UPI_CPU0_CPU1_P1P0_DN<13>")
		)
		(pad "CW9" smd circle
			(at -30.914086 9.578086 270)
			(size 0.4318 0.4318)
			(layers "F.Cu" "F.Mask" "F.Paste")
			(net "GND")
		)
		(pad "CW11" smd circle
			(at -29.2862 9.578086 270)
			(size 0.4318 0.4318)
			(layers "F.Cu" "F.Mask" "F.Paste")
			(net "P5E_CPU0_PE2_RX_DP<1>")
		)
		(pad "CW13" smd circle
			(at -27.658314 9.578086 270)
			(size 0.4318 0.4318)
			(layers "F.Cu" "F.Mask" "F.Paste")
			(net "GND")
		)
		(pad "CW15" smd circle
			(at -26.030682 9.578086 270)
			(size 0.4318 0.4318)
			(layers "F.Cu" "F.Mask" "F.Paste")
			(net "P5E_CPU0_PE2_TX_DP<1>")
		)
		(pad "CW17" smd circle
			(at -24.402796 9.578086 270)
			(size 0.4318 0.4318)
			(layers "F.Cu" "F.Mask" "F.Paste")
			(net "GND")
		)
		(pad "CW19" smd circle
			(at -22.77491 9.578086 270)
			(size 0.4318 0.4318)
			(layers "F.Cu" "F.Mask" "F.Paste")
			(net "PU_CPU0_UPI1_AC_COUPLING")
		)
		(pad "CW21" smd circle
			(at -21.147278 9.578086 270)
			(size 0.4318 0.4318)
			(layers "F.Cu" "F.Mask" "F.Paste")
			(net "TP_IBL_SLPS5_CPU0_R_N")
		)
		(pad "CW23" smd circle
			(at -19.519392 9.578086 270)
			(size 0.4318 0.4318)
			(layers "F.Cu" "F.Mask" "F.Paste")
			(net "NC_CPU0_VIEWPIN_DIE10<3>")
		)
		(pad "CW25" smd circle
			(at -17.89176 9.578086 270)
			(size 0.4318 0.4318)
			(layers "F.Cu" "F.Mask" "F.Paste")
			(net "NC_CPU0_VIEWPIN_DIE10<1>")
		)
		(pad "CW27" smd circle
			(at -16.263874 9.578086 270)
			(size 0.4318 0.4318)
			(layers "F.Cu" "F.Mask" "F.Paste")
			(net "CLK_100M_DB2000_CPU0_BCLK3_DN")
		)
		(pad "CW29" smd circle
			(at -14.635988 9.578086 270)
			(size 0.4318 0.4318)
			(layers "F.Cu" "F.Mask" "F.Paste")
			(net "CLK_100M_DB2000_CPU0_BCLK1_DP")
		)
		(pad "CW31" smd circle
			(at -13.008356 9.578086 270)
			(size 0.4318 0.4318)
			(layers "F.Cu" "F.Mask" "F.Paste")
			(net "CLK_25M_NSSC_CPU0_DN")
		)
		(pad "CW33" smd circle
			(at -11.380724 9.578086 270)
			(size 0.4318 0.4318)
			(layers "F.Cu" "F.Mask" "F.Paste")
			(net "GND")
		)
		(pad "CW35" smd circle
			(at -9.752838 9.578086 270)
			(size 0.4318 0.4318)
			(layers "F.Cu" "F.Mask" "F.Paste")
			(net "PVCCD_HV_CPU0")
		)
		(pad "CW37" smd circle
			(at -8.124952 9.578086 270)
			(size 0.4318 0.4318)
			(layers "F.Cu" "F.Mask" "F.Paste")
			(net "PVCCD_HV_CPU0")
		)
		(pad "CW39" smd circle
			(at -6.49732 9.578086 270)
			(size 0.4318 0.4318)
			(layers "F.Cu" "F.Mask" "F.Paste")
			(net "H_CPU0_PMDOWN_CPU1_R")
		)
		(pad "CW41" smd circle
			(at -4.869434 9.578086 270)
			(size 0.4318 0.4318)
			(layers "F.Cu" "F.Mask" "F.Paste")
			(net "NC_CPU0_HBM1_VIEWDIG1")
		)
		(pad "CW43" smd circle
			(at -3.241802 9.578086 270)
			(size 0.4318 0.4318)
			(layers "F.Cu" "F.Mask" "F.Paste")
			(net "TP_CPU0_SPARE6")
		)
		(pad "CW45" smd circle
			(at -1.613916 9.578086 270)
			(size 0.4318 0.4318)
			(layers "F.Cu" "F.Mask" "F.Paste")
			(net "PWRGD_DRAMPWRGD_CPU0_GH_LVC1_R")
		)
		(pad "CW48" smd circle
			(at 2.427732 9.688068 270)
			(size 0.4318 0.4318)
			(layers "F.Cu" "F.Mask" "F.Paste")
			(net "M_F_CPU0_ALERT_N")
		)
		(pad "CW50" smd circle
			(at 4.055618 9.688068 270)
			(size 0.4318 0.4318)
			(layers "F.Cu" "F.Mask" "F.Paste")
			(net "M_G_CPU0_ALERT_N")
		)
		(pad "CW52" smd circle
			(at 5.68325 9.688068 270)
			(size 0.4318 0.4318)
			(layers "F.Cu" "F.Mask" "F.Paste")
			(net "PVCCD_HV_CPU0")
		)
		(pad "CW54" smd circle
			(at 7.311136 9.688068 270)
			(size 0.4318 0.4318)
			(layers "F.Cu" "F.Mask" "F.Paste")
			(net "PVCCD_HV_CPU0")
		)
		(pad "CW56" smd circle
			(at 8.939022 9.688068 270)
			(size 0.4318 0.4318)
			(layers "F.Cu" "F.Mask" "F.Paste")
			(net "PVCCD_HV_CPU0")
		)
		(pad "CW58" smd circle
			(at 10.566654 9.688068 270)
			(size 0.4318 0.4318)
			(layers "F.Cu" "F.Mask" "F.Paste")
			(net "NC_CPU0_VIEWPIN_GNR1")
		)
		(pad "CW60" smd circle
			(at 12.19454 9.688068 270)
			(size 0.4318 0.4318)
			(layers "F.Cu" "F.Mask" "F.Paste")
			(net "PU_CPU0_SOCKET_ID0")
		)
		(pad "CW62" smd circle
			(at 13.822426 9.688068 270)
			(size 0.4318 0.4318)
			(layers "F.Cu" "F.Mask" "F.Paste")
			(net "PVCCINFAON_CPU0")
		)
		(pad "CW64" smd circle
			(at 15.450058 9.688068 270)
			(size 0.4318 0.4318)
			(layers "F.Cu" "F.Mask" "F.Paste")
			(net "PVCCINFAON_CPU0")
		)
		(pad "CW66" smd circle
			(at 17.07769 9.688068 270)
			(size 0.4318 0.4318)
			(layers "F.Cu" "F.Mask" "F.Paste")
			(net "PVCCINFAON_CPU0")
		)
		(pad "CW68" smd circle
			(at 18.705576 9.688068 270)
			(size 0.4318 0.4318)
			(layers "F.Cu" "F.Mask" "F.Paste")
			(net "NC_CPU0_RSVD<144>")
		)
		(pad "CW70" smd circle
			(at 20.333462 9.688068 270)
			(size 0.4318 0.4318)
			(layers "F.Cu" "F.Mask" "F.Paste")
			(net "GND")
		)
		(pad "CW72" smd circle
			(at 21.961094 9.688068 270)
			(size 0.4318 0.4318)
			(layers "F.Cu" "F.Mask" "F.Paste")
			(net "GND")
		)
		(pad "CW74" smd circle
			(at 23.58898 9.688068 270)
			(size 0.4318 0.4318)
			(layers "F.Cu" "F.Mask" "F.Paste")
			(net "Net_662")
		)
		(pad "CW76" smd circle
			(at 25.216612 9.688068 270)
			(size 0.4318 0.4318)
			(layers "F.Cu" "F.Mask" "F.Paste")
			(net "Net_697")
		)
		(pad "CW78" smd circle
			(at 26.844498 9.688068 270)
			(size 0.4318 0.4318)
			(layers "F.Cu" "F.Mask" "F.Paste")
			(net "GND")
		)
		(pad "CW80" smd circle
			(at 28.472384 9.688068 270)
			(size 0.4318 0.4318)
			(layers "F.Cu" "F.Mask" "F.Paste")
			(net "GND")
		)
		(pad "CW82" smd circle
			(at 30.100016 9.688068 270)
			(size 0.4318 0.4318)
			(layers "F.Cu" "F.Mask" "F.Paste")
			(net "GND")
		)
		(pad "CW84" smd circle
			(at 31.727902 9.688068 270)
			(size 0.4318 0.4318)
			(layers "F.Cu" "F.Mask" "F.Paste")
			(net "GND")
		)
		(pad "CW86" smd circle
			(at 33.355534 9.688068 270)
			(size 0.4318 0.4318)
			(layers "F.Cu" "F.Mask" "F.Paste")
			(net "P5E_CPU0_PE3_TX_DP<13>")
		)
		(pad "CW88" smd circle
			(at 34.98342 9.688068 270)
			(size 0.4318 0.4318)
			(layers "F.Cu" "F.Mask" "F.Paste")
			(net "GND")
		)
		(pad "CW90" smd circle
			(at 36.611306 9.688068 270)
			(size 0.4318 0.4318)
			(layers "F.Cu" "F.Mask" "F.Paste")
			(net "P5E_CPU0_PE3_RX_DP<14>")
		)
		(pad "CY2" smd circle
			(at -36.611306 10.047732 270)
			(size 0.4318 0.4318)
			(layers "F.Cu" "F.Mask" "F.Paste")
			(net "UPI_CPU1_CPU0_P0P1_DN<14>")
		)
		(pad "CY4" smd circle
			(at -34.98342 10.047732 270)
			(size 0.4318 0.4318)
			(layers "F.Cu" "F.Mask" "F.Paste")
			(net "GND")
		)
		(pad "CY6" smd circle
			(at -33.355534 10.047732 270)
			(size 0.4318 0.4318)
			(layers "F.Cu" "F.Mask" "F.Paste")
			(net "UPI_CPU0_CPU1_P1P0_DP<13>")
		)
		(pad "CY8" smd circle
			(at -31.727902 10.047732 270)
			(size 0.4318 0.4318)
			(layers "F.Cu" "F.Mask" "F.Paste")
			(net "GND")
		)
		(pad "CY10" smd circle
			(at -30.100016 10.047732 270)
			(size 0.4318 0.4318)
			(layers "F.Cu" "F.Mask" "F.Paste")
			(net "P5E_CPU0_PE2_RX_DN<1>")
		)
		(pad "CY12" smd circle
			(at -28.472384 10.047732 270)
			(size 0.4318 0.4318)
			(layers "F.Cu" "F.Mask" "F.Paste")
			(net "GND")
		)
		(pad "CY14" smd circle
			(at -26.844498 10.047732 270)
			(size 0.4318 0.4318)
			(layers "F.Cu" "F.Mask" "F.Paste")
			(net "P5E_CPU0_PE2_TX_DP<2>")
		)
		(pad "CY16" smd circle
			(at -25.216612 10.047732 270)
			(size 0.4318 0.4318)
			(layers "F.Cu" "F.Mask" "F.Paste")
			(net "GND")
		)
		(pad "CY18" smd circle
			(at -23.58898 10.047732 270)
			(size 0.4318 0.4318)
			(layers "F.Cu" "F.Mask" "F.Paste")
			(net "GND")
		)
		(pad "CY20" smd circle
			(at -21.961094 10.047732 270)
			(size 0.4318 0.4318)
			(layers "F.Cu" "F.Mask" "F.Paste")
			(net "FM_S3M_CPU0_CPLD_CRC_ERROR")
		)
		(pad "CY22" smd circle
			(at -20.333462 10.047732 270)
			(size 0.4318 0.4318)
			(layers "F.Cu" "F.Mask" "F.Paste")
			(net "PD_JTAG_CPU0_PLD_TCK")
		)
		(pad "CY24" smd circle
			(at -18.705576 10.047732 270)
			(size 0.4318 0.4318)
			(layers "F.Cu" "F.Mask" "F.Paste")
			(net "NC_CPU0_DDR45_VIEWDIG0")
		)
		(pad "CY26" smd circle
			(at -17.07769 10.047732 270)
			(size 0.4318 0.4318)
			(layers "F.Cu" "F.Mask" "F.Paste")
			(net "GND")
		)
		(pad "CY28" smd circle
			(at -15.450058 10.047732 270)
			(size 0.4318 0.4318)
			(layers "F.Cu" "F.Mask" "F.Paste")
			(net "CLK_100M_DB2000_CPU0_BCLK1_DN")
		)
		(pad "CY30" smd circle
			(at -13.822426 10.047732 270)
			(size 0.4318 0.4318)
			(layers "F.Cu" "F.Mask" "F.Paste")
			(net "GND")
		)
		(pad "CY32" smd circle
			(at -12.19454 10.047732 270)
			(size 0.4318 0.4318)
			(layers "F.Cu" "F.Mask" "F.Paste")
			(net "CLK_25M_NSSC_CPU0_DP")
		)
		(pad "CY34" smd circle
			(at -10.566654 10.047732 270)
			(size 0.4318 0.4318)
			(layers "F.Cu" "F.Mask" "F.Paste")
			(net "PVCCD_HV_CPU0")
		)
		(pad "CY36" smd circle
			(at -8.939022 10.047732 270)
			(size 0.4318 0.4318)
			(layers "F.Cu" "F.Mask" "F.Paste")
			(net "PVCCD_HV_CPU0")
		)
		(pad "CY38" smd circle
			(at -7.311136 10.047732 270)
			(size 0.4318 0.4318)
			(layers "F.Cu" "F.Mask" "F.Paste")
			(net "NC_CPU0_DDR45_VIEWDIG1")
		)
		(pad "CY40" smd circle
			(at -5.68325 10.047732 270)
			(size 0.4318 0.4318)
			(layers "F.Cu" "F.Mask" "F.Paste")
			(net "H_CPU0_PMDOWN_PCH_R2")
		)
		(pad "CY42" smd circle
			(at -4.055618 10.047732 270)
			(size 0.4318 0.4318)
			(layers "F.Cu" "F.Mask" "F.Paste")
			(net "RST_CPU0_DRAM_EF_N")
		)
		(pad "CY44" smd circle
			(at -2.427732 10.047732 270)
			(size 0.4318 0.4318)
			(layers "F.Cu" "F.Mask" "F.Paste")
			(net "PWRGD_DRAMPWRGD_CPU0_EF_LVC1_R")
		)
		(pad "CY47" smd circle
			(at 1.613916 10.157714 270)
			(size 0.4318 0.4318)
			(layers "F.Cu" "F.Mask" "F.Paste")
			(net "M_E_CPU0_ALERT_N")
		)
		(pad "CY49" smd circle
			(at 3.241802 10.157714 270)
			(size 0.4318 0.4318)
			(layers "F.Cu" "F.Mask" "F.Paste")
			(net "NC_CPU0_DDR67_VIEWDIG1")
		)
		(pad "CY51" smd circle
			(at 4.869434 10.157714 270)
			(size 0.4318 0.4318)
			(layers "F.Cu" "F.Mask" "F.Paste")
			(net "M_H_CPU0_ALERT_N")
		)
		(pad "CY53" smd circle
			(at 6.49732 10.157714 270)
			(size 0.4318 0.4318)
			(layers "F.Cu" "F.Mask" "F.Paste")
			(net "PVCCD_HV_CPU0")
		)
		(pad "CY55" smd circle
			(at 8.124952 10.157714 270)
			(size 0.4318 0.4318)
			(layers "F.Cu" "F.Mask" "F.Paste")
			(net "RST_CPU0_DRAM_GH_N")
		)
		(pad "CY57" smd circle
			(at 9.752838 10.157714 270)
			(size 0.4318 0.4318)
			(layers "F.Cu" "F.Mask" "F.Paste")
			(net "NC_CPU0_VIEWPIN_GNR3")
		)
		(pad "CY59" smd circle
			(at 11.380724 10.157714 270)
			(size 0.4318 0.4318)
			(layers "F.Cu" "F.Mask" "F.Paste")
			(net "PU_CPU0_LEGACY_SKT")
		)
		(pad "CY61" smd circle
			(at 13.008356 10.157714 270)
			(size 0.4318 0.4318)
			(layers "F.Cu" "F.Mask" "F.Paste")
			(net "PU_CPU0_SOCKET_ID1")
		)
		(pad "CY63" smd circle
			(at 14.635988 10.157714 270)
			(size 0.4318 0.4318)
			(layers "F.Cu" "F.Mask" "F.Paste")
			(net "GND")
		)
		(pad "CY65" smd circle
			(at 16.263874 10.157714 270)
			(size 0.4318 0.4318)
			(layers "F.Cu" "F.Mask" "F.Paste")
			(net "PVCCINFAON_CPU0")
		)
		(pad "CY67" smd circle
			(at 17.89176 10.157714 270)
			(size 0.4318 0.4318)
			(layers "F.Cu" "F.Mask" "F.Paste")
			(net "PVCCINFAON_CPU0")
		)
		(pad "CY69" smd circle
			(at 19.519392 10.157714 270)
			(size 0.4318 0.4318)
			(layers "F.Cu" "F.Mask" "F.Paste")
			(net "NC_UART_IBL_CPU0_RXD")
		)
		(pad "CY71" smd circle
			(at 21.147278 10.157714 270)
			(size 0.4318 0.4318)
			(layers "F.Cu" "F.Mask" "F.Paste")
			(net "NC_UART_IBL_CPU0_RTS")
		)
		(pad "CY73" smd circle
			(at 22.77491 10.157714 270)
			(size 0.4318 0.4318)
			(layers "F.Cu" "F.Mask" "F.Paste")
			(net "GND")
		)
		(pad "CY75" smd circle
			(at 24.402796 10.157714 270)
			(size 0.4318 0.4318)
			(layers "F.Cu" "F.Mask" "F.Paste")
			(net "PVCCFA_EHV_FIVRA_CPU0")
		)
		(pad "CY77" smd circle
			(at 26.030682 10.157714 270)
			(size 0.4318 0.4318)
			(layers "F.Cu" "F.Mask" "F.Paste")
			(net "GND")
		)
		(pad "CY79" smd circle
			(at 27.658314 10.157714 270)
			(size 0.4318 0.4318)
			(layers "F.Cu" "F.Mask" "F.Paste")
			(net "PVCCFA_EHV_FIVRA_CPU0")
		)
		(pad "CY81" smd circle
			(at 29.2862 10.157714 270)
			(size 0.4318 0.4318)
			(layers "F.Cu" "F.Mask" "F.Paste")
			(net "GND")
		)
		(pad "CY83" smd circle
			(at 30.914086 10.157714 270)
			(size 0.4318 0.4318)
			(layers "F.Cu" "F.Mask" "F.Paste")
			(net "GND")
		)
		(pad "CY85" smd circle
			(at 32.541718 10.157714 270)
			(size 0.4318 0.4318)
			(layers "F.Cu" "F.Mask" "F.Paste")
			(net "PVCCFA_EHV_FIVRA_CPU0")
		)
		(pad "CY87" smd circle
			(at 34.169604 10.157714 270)
			(size 0.4318 0.4318)
			(layers "F.Cu" "F.Mask" "F.Paste")
			(net "P5E_CPU0_PE3_TX_DN<12>")
		)
		(pad "CY89" smd circle
			(at 35.797236 10.157714 270)
			(size 0.4318 0.4318)
			(layers "F.Cu" "F.Mask" "F.Paste")
			(net "PVCCFA_EHV_FIVRA_CPU0")
		)
		(pad "CY91" smd oval
			(at 37.425122 10.157714)
			(size 0.381 0.4826)
			(drill
				(offset 0 -0.0508)
			)
			(layers "F.Cu" "F.Mask" "F.Paste")
			(net "P5E_CPU0_PE3_RX_DP<13>")
		)
		(pad "D4" smd oval
			(at -34.98342 -25.664414 135)
			(size 0.381 0.4826)
			(drill
				(offset 0 -0.0508)
			)
			(layers "F.Cu" "F.Mask" "F.Paste")
			(net "NC_XTAL_CPU0_25M_OUT")
		)
		(pad "D6" smd oval
			(at -33.355534 -25.664414 135)
			(size 0.381 0.4826)
			(drill
				(offset 0 -0.0508)
			)
			(layers "F.Cu" "F.Mask" "F.Paste")
			(net "GND")
		)
		(pad "D8" smd oval
			(at -31.727902 -25.664414 135)
			(size 0.381 0.4826)
			(drill
				(offset 0 -0.0508)
			)
			(layers "F.Cu" "F.Mask" "F.Paste")
			(net "GND")
		)
		(pad "D10" smd circle
			(at -30.100016 -25.664414 270)
			(size 0.4318 0.4318)
			(layers "F.Cu" "F.Mask" "F.Paste")
			(net "GND")
		)
		(pad "D12" smd circle
			(at -28.472384 -25.664414 270)
			(size 0.4318 0.4318)
			(layers "F.Cu" "F.Mask" "F.Paste")
			(net "GND")
		)
		(pad "D14" smd circle
			(at -26.844498 -25.664414 270)
			(size 0.4318 0.4318)
			(layers "F.Cu" "F.Mask" "F.Paste")
			(net "GND")
		)
		(pad "D16" smd circle
			(at -25.216612 -25.664414 270)
			(size 0.4318 0.4318)
			(layers "F.Cu" "F.Mask" "F.Paste")
			(net "GND")
		)
		(pad "D18" smd circle
			(at -23.58898 -25.664414 270)
			(size 0.4318 0.4318)
			(layers "F.Cu" "F.Mask" "F.Paste")
			(net "GND")
		)
		(pad "D20" smd circle
			(at -21.961094 -25.664414 270)
			(size 0.4318 0.4318)
			(layers "F.Cu" "F.Mask" "F.Paste")
			(net "GND")
		)
		(pad "D22" smd circle
			(at -20.333462 -25.664414 270)
			(size 0.4318 0.4318)
			(layers "F.Cu" "F.Mask" "F.Paste")
			(net "GND")
		)
		(pad "D24" smd circle
			(at -18.705576 -25.664414 270)
			(size 0.4318 0.4318)
			(layers "F.Cu" "F.Mask" "F.Paste")
			(net "GND")
		)
		(pad "D26" smd circle
			(at -17.07769 -25.664414 270)
			(size 0.4318 0.4318)
			(layers "F.Cu" "F.Mask" "F.Paste")
			(net "GND")
		)
		(pad "D28" smd circle
			(at -15.450058 -25.664414 270)
			(size 0.4318 0.4318)
			(layers "F.Cu" "F.Mask" "F.Paste")
			(net "GND")
		)
		(pad "D30" smd circle
			(at -13.822426 -25.664414 270)
			(size 0.4318 0.4318)
			(layers "F.Cu" "F.Mask" "F.Paste")
			(net "GND")
		)
	)
)
